FILE_TYPE=LIBRARY_PARTS;
primitive 'FCONN168_ME1016810202011_SCM';
  pin
    'P12V_AUX_OA1':
      PIN_NUMBER='(OA1)';
      PINUSE='POWER';
      NO_LOAD_CHECK='Both';
      NO_IO_CHECK='Both';
      NO_ASSERT_CHECK='TRUE';
      NO_DIR_CHECK='TRUE';
      ALLOW_CONNECT='TRUE';
    'P12V_AUX_OA2':
      PIN_NUMBER='(OA2)';
      PINUSE='POWER';
      NO_LOAD_CHECK='Both';
      NO_IO_CHECK='Both';
      NO_ASSERT_CHECK='TRUE';
      NO_DIR_CHECK='TRUE';
      ALLOW_CONNECT='TRUE';
    'GND_OA3':
      PIN_NUMBER='(OA3)';
      PINUSE='POWER';
      NO_LOAD_CHECK='Both';
      NO_IO_CHECK='Both';
      NO_ASSERT_CHECK='TRUE';
      NO_DIR_CHECK='TRUE';
      ALLOW_CONNECT='TRUE';
    'GND_OA4':
      PIN_NUMBER='(OA4)';
      PINUSE='POWER';
      NO_LOAD_CHECK='Both';
      NO_IO_CHECK='Both';
      NO_ASSERT_CHECK='TRUE';
      NO_DIR_CHECK='TRUE';
      ALLOW_CONNECT='TRUE';
    'I3C_0_SCL':
      PIN_NUMBER='(OA5)';
      BIDIRECTIONAL='TRUE';
      INPUT_LOAD='(-0.01,0.01)';
      OUTPUT_LOAD='(1.0,-1.0)';
    'I3C_0_SDA':
      PIN_NUMBER='(OA6)';
      BIDIRECTIONAL='TRUE';
      INPUT_LOAD='(-0.01,0.01)';
      OUTPUT_LOAD='(1.0,-1.0)';
    'I3C_1_SCL':
      PIN_NUMBER='(OA7)';
      BIDIRECTIONAL='TRUE';
      INPUT_LOAD='(-0.01,0.01)';
      OUTPUT_LOAD='(1.0,-1.0)';
    'I3C_1_SDA':
      PIN_NUMBER='(OA8)';
      BIDIRECTIONAL='TRUE';
      INPUT_LOAD='(-0.01,0.01)';
      OUTPUT_LOAD='(1.0,-1.0)';
    'I3C_2_SCL':
      PIN_NUMBER='(OA9)';
      BIDIRECTIONAL='TRUE';
      INPUT_LOAD='(-0.01,0.01)';
      OUTPUT_LOAD='(1.0,-1.0)';
    'I3C_2_SDA':
      PIN_NUMBER='(OA10)';
      BIDIRECTIONAL='TRUE';
      INPUT_LOAD='(-0.01,0.01)';
      OUTPUT_LOAD='(1.0,-1.0)';
    'I3C_3_SCL':
      PIN_NUMBER='(OA11)';
      BIDIRECTIONAL='TRUE';
      INPUT_LOAD='(-0.01,0.01)';
      OUTPUT_LOAD='(1.0,-1.0)';
    'I3C_3_SDA':
      PIN_NUMBER='(OA12)';
      BIDIRECTIONAL='TRUE';
      INPUT_LOAD='(-0.01,0.01)';
      OUTPUT_LOAD='(1.0,-1.0)';
    'GND_OA13':
      PIN_NUMBER='(OA13)';
      PINUSE='POWER';
      NO_LOAD_CHECK='Both';
      NO_IO_CHECK='Both';
      NO_ASSERT_CHECK='TRUE';
      NO_DIR_CHECK='TRUE';
      ALLOW_CONNECT='TRUE';
    'VIRTUAL_RESEAT':
      PIN_NUMBER='(OA14)';
      BIDIRECTIONAL='TRUE';
      INPUT_LOAD='(-0.01,0.01)';
      OUTPUT_LOAD='(1.0,-1.0)';
    'I2C_0_SCL':
      PIN_NUMBER='(A1)';
      BIDIRECTIONAL='TRUE';
      INPUT_LOAD='(-0.01,0.01)';
      OUTPUT_LOAD='(1.0,-1.0)';
    'I2C_0_SDA':
      PIN_NUMBER='(A2)';
      BIDIRECTIONAL='TRUE';
      INPUT_LOAD='(-0.01,0.01)';
      OUTPUT_LOAD='(1.0,-1.0)';
    'I2C_1_SCL':
      PIN_NUMBER='(A3)';
      BIDIRECTIONAL='TRUE';
      INPUT_LOAD='(-0.01,0.01)';
      OUTPUT_LOAD='(1.0,-1.0)';
    'I2C_1_SDA':
      PIN_NUMBER='(A4)';
      BIDIRECTIONAL='TRUE';
      INPUT_LOAD='(-0.01,0.01)';
      OUTPUT_LOAD='(1.0,-1.0)';
    'I2C_2_SCL':
      PIN_NUMBER='(A5)';
      BIDIRECTIONAL='TRUE';
      INPUT_LOAD='(-0.01,0.01)';
      OUTPUT_LOAD='(1.0,-1.0)';
    'I2C_2_SDA':
      PIN_NUMBER='(A6)';
      BIDIRECTIONAL='TRUE';
      INPUT_LOAD='(-0.01,0.01)';
      OUTPUT_LOAD='(1.0,-1.0)';
    'I2C_3_SCL':
      PIN_NUMBER='(A7)';
      BIDIRECTIONAL='TRUE';
      INPUT_LOAD='(-0.01,0.01)';
      OUTPUT_LOAD='(1.0,-1.0)';
    'I2C_3_SDA':
      PIN_NUMBER='(A8)';
      BIDIRECTIONAL='TRUE';
      INPUT_LOAD='(-0.01,0.01)';
      OUTPUT_LOAD='(1.0,-1.0)';
    'I2C_4_SCL':
      PIN_NUMBER='(A9)';
      BIDIRECTIONAL='TRUE';
      INPUT_LOAD='(-0.01,0.01)';
      OUTPUT_LOAD='(1.0,-1.0)';
    'I2C_4_SDA':
      PIN_NUMBER='(A10)';
      BIDIRECTIONAL='TRUE';
      INPUT_LOAD='(-0.01,0.01)';
      OUTPUT_LOAD='(1.0,-1.0)';
    'I2C_5_SCL':
      PIN_NUMBER='(A11)';
      BIDIRECTIONAL='TRUE';
      INPUT_LOAD='(-0.01,0.01)';
      OUTPUT_LOAD='(1.0,-1.0)';
    'I2C_5_SDA':
      PIN_NUMBER='(A12)';
      BIDIRECTIONAL='TRUE';
      INPUT_LOAD='(-0.01,0.01)';
      OUTPUT_LOAD='(1.0,-1.0)';
    'GND_A13':
      PIN_NUMBER='(A13)';
      PINUSE='POWER';
      NO_LOAD_CHECK='Both';
      NO_IO_CHECK='Both';
      NO_ASSERT_CHECK='TRUE';
      NO_DIR_CHECK='TRUE';
      ALLOW_CONNECT='TRUE';
    'CLK_100M_PCIE_DP':
      PIN_NUMBER='(A14)';
      BIDIRECTIONAL='TRUE';
      INPUT_LOAD='(-0.01,0.01)';
      OUTPUT_LOAD='(1.0,-1.0)';
    'CLK_100M_PCIE_DN':
      PIN_NUMBER='(A15)';
      BIDIRECTIONAL='TRUE';
      INPUT_LOAD='(-0.01,0.01)';
      OUTPUT_LOAD='(1.0,-1.0)';
    'GND_A16':
      PIN_NUMBER='(A16)';
      PINUSE='POWER';
      NO_LOAD_CHECK='Both';
      NO_IO_CHECK='Both';
      NO_ASSERT_CHECK='TRUE';
      NO_DIR_CHECK='TRUE';
      ALLOW_CONNECT='TRUE';
    'PCIE_BMC_TX_DP':
      PIN_NUMBER='(A17)';
      BIDIRECTIONAL='TRUE';
      INPUT_LOAD='(-0.01,0.01)';
      OUTPUT_LOAD='(1.0,-1.0)';
    'PCIE_BMC_TX_DN':
      PIN_NUMBER='(A18)';
      BIDIRECTIONAL='TRUE';
      INPUT_LOAD='(-0.01,0.01)';
      OUTPUT_LOAD='(1.0,-1.0)';
    'GND_A19':
      PIN_NUMBER='(A19)';
      PINUSE='POWER';
      NO_LOAD_CHECK='Both';
      NO_IO_CHECK='Both';
      NO_ASSERT_CHECK='TRUE';
      NO_DIR_CHECK='TRUE';
      ALLOW_CONNECT='TRUE';
    'PCIE_BMC_RX_DP':
      PIN_NUMBER='(A20)';
      BIDIRECTIONAL='TRUE';
      INPUT_LOAD='(-0.01,0.01)';
      OUTPUT_LOAD='(1.0,-1.0)';
    'PCIE_BMC_RX_DN':
      PIN_NUMBER='(A21)';
      BIDIRECTIONAL='TRUE';
      INPUT_LOAD='(-0.01,0.01)';
      OUTPUT_LOAD='(1.0,-1.0)';
    'GND_A22':
      PIN_NUMBER='(A22)';
      PINUSE='POWER';
      NO_LOAD_CHECK='Both';
      NO_IO_CHECK='Both';
      NO_ASSERT_CHECK='TRUE';
      NO_DIR_CHECK='TRUE';
      ALLOW_CONNECT='TRUE';
    'I2C_6_SCL':
      PIN_NUMBER='(A23)';
      BIDIRECTIONAL='TRUE';
      INPUT_LOAD='(-0.01,0.01)';
      OUTPUT_LOAD='(1.0,-1.0)';
    'I2C_6_SDA':
      PIN_NUMBER='(A24)';
      BIDIRECTIONAL='TRUE';
      INPUT_LOAD='(-0.01,0.01)';
      OUTPUT_LOAD='(1.0,-1.0)';
    'I2C_7_SCL':
      PIN_NUMBER='(A25)';
      BIDIRECTIONAL='TRUE';
      INPUT_LOAD='(-0.01,0.01)';
      OUTPUT_LOAD='(1.0,-1.0)';
    'I2C_7_SDA':
      PIN_NUMBER='(A26)';
      BIDIRECTIONAL='TRUE';
      INPUT_LOAD='(-0.01,0.01)';
      OUTPUT_LOAD='(1.0,-1.0)';
    'I2C_8_SCL':
      PIN_NUMBER='(A27)';
      BIDIRECTIONAL='TRUE';
      INPUT_LOAD='(-0.01,0.01)';
      OUTPUT_LOAD='(1.0,-1.0)';
    'I2C_8_SDA':
      PIN_NUMBER='(A28)';
      BIDIRECTIONAL='TRUE';
      INPUT_LOAD='(-0.01,0.01)';
      OUTPUT_LOAD='(1.0,-1.0)';
    'I2C_9_SCL':
      PIN_NUMBER='(A29)';
      BIDIRECTIONAL='TRUE';
      INPUT_LOAD='(-0.01,0.01)';
      OUTPUT_LOAD='(1.0,-1.0)';
    'I2C_9_SDA':
      PIN_NUMBER='(A30)';
      BIDIRECTIONAL='TRUE';
      INPUT_LOAD='(-0.01,0.01)';
      OUTPUT_LOAD='(1.0,-1.0)';
    'I2C_10_SCL':
      PIN_NUMBER='(A31)';
      BIDIRECTIONAL='TRUE';
      INPUT_LOAD='(-0.01,0.01)';
      OUTPUT_LOAD='(1.0,-1.0)';
    'I2C_10_SDA':
      PIN_NUMBER='(A32)';
      BIDIRECTIONAL='TRUE';
      INPUT_LOAD='(-0.01,0.01)';
      OUTPUT_LOAD='(1.0,-1.0)';
    'GND_A33':
      PIN_NUMBER='(A33)';
      PINUSE='POWER';
      NO_LOAD_CHECK='Both';
      NO_IO_CHECK='Both';
      NO_ASSERT_CHECK='TRUE';
      NO_DIR_CHECK='TRUE';
      ALLOW_CONNECT='TRUE';
    'JTAG_TCK':
      PIN_NUMBER='(A34)';
      BIDIRECTIONAL='TRUE';
      INPUT_LOAD='(-0.01,0.01)';
      OUTPUT_LOAD='(1.0,-1.0)';
    'JTAG_TMS':
      PIN_NUMBER='(A35)';
      BIDIRECTIONAL='TRUE';
      INPUT_LOAD='(-0.01,0.01)';
      OUTPUT_LOAD='(1.0,-1.0)';
    'JTAG_TDI':
      PIN_NUMBER='(A36)';
      BIDIRECTIONAL='TRUE';
      INPUT_LOAD='(-0.01,0.01)';
      OUTPUT_LOAD='(1.0,-1.0)';
    'JTAG_TDO':
      PIN_NUMBER='(A37)';
      BIDIRECTIONAL='TRUE';
      INPUT_LOAD='(-0.01,0.01)';
      OUTPUT_LOAD='(1.0,-1.0)';
    'I2C_11_SCL':
      PIN_NUMBER='(A38)';
      BIDIRECTIONAL='TRUE';
      INPUT_LOAD='(-0.01,0.01)';
      OUTPUT_LOAD='(1.0,-1.0)';
    'I2C_11_SDA':
      PIN_NUMBER='(A39)';
      BIDIRECTIONAL='TRUE';
      INPUT_LOAD='(-0.01,0.01)';
      OUTPUT_LOAD='(1.0,-1.0)';
    'I2C_12_SCL':
      PIN_NUMBER='(A40)';
      BIDIRECTIONAL='TRUE';
      INPUT_LOAD='(-0.01,0.01)';
      OUTPUT_LOAD='(1.0,-1.0)';
    'I2C_12_SDA':
      PIN_NUMBER='(A41)';
      BIDIRECTIONAL='TRUE';
      INPUT_LOAD='(-0.01,0.01)';
      OUTPUT_LOAD='(1.0,-1.0)';
    'GND_A42':
      PIN_NUMBER='(A42)';
      PINUSE='POWER';
      NO_LOAD_CHECK='Both';
      NO_IO_CHECK='Both';
      NO_ASSERT_CHECK='TRUE';
      NO_DIR_CHECK='TRUE';
      ALLOW_CONNECT='TRUE';
    'HPM_FW_RECOVERY':
      PIN_NUMBER='(A43)';
      BIDIRECTIONAL='TRUE';
      INPUT_LOAD='(-0.01,0.01)';
      OUTPUT_LOAD='(1.0,-1.0)';
    'HPM_STBY_RDY':
      PIN_NUMBER='(A44)';
      BIDIRECTIONAL='TRUE';
      INPUT_LOAD='(-0.01,0.01)';
      OUTPUT_LOAD='(1.0,-1.0)';
    'HPM_STBY_EN':
      PIN_NUMBER='(A45)';
      BIDIRECTIONAL='TRUE';
      INPUT_LOAD='(-0.01,0.01)';
      OUTPUT_LOAD='(1.0,-1.0)';
    '-HPM_STBY_RST':
      PIN_NUMBER='(A46)';
      BIDIRECTIONAL='TRUE';
      INPUT_LOAD='(-0.01,0.01)';
      OUTPUT_LOAD='(1.0,-1.0)';
    '-SYS_PWRBTN':
      PIN_NUMBER='(A47)';
      BIDIRECTIONAL='TRUE';
      INPUT_LOAD='(-0.01,0.01)';
      OUTPUT_LOAD='(1.0,-1.0)';
    'SYS_PWROK':
      PIN_NUMBER='(A48)';
      BIDIRECTIONAL='TRUE';
      INPUT_LOAD='(-0.01,0.01)';
      OUTPUT_LOAD='(1.0,-1.0)';
    '-DBP_PREQ':
      PIN_NUMBER='(A49)';
      BIDIRECTIONAL='TRUE';
      INPUT_LOAD='(-0.01,0.01)';
      OUTPUT_LOAD='(1.0,-1.0)';
    '-DBP_PRDY':
      PIN_NUMBER='(A50)';
      BIDIRECTIONAL='TRUE';
      INPUT_LOAD='(-0.01,0.01)';
      OUTPUT_LOAD='(1.0,-1.0)';
    '-RST_PLTRST_BUF':
      PIN_NUMBER='(A51)';
      BIDIRECTIONAL='TRUE';
      INPUT_LOAD='(-0.01,0.01)';
      OUTPUT_LOAD='(1.0,-1.0)';
    'SPARE1':
      PIN_NUMBER='(A52)';
      BIDIRECTIONAL='TRUE';
      INPUT_LOAD='(-0.01,0.01)';
      OUTPUT_LOAD='(1.0,-1.0)';
    '-ROT_CPU_RST':
      PIN_NUMBER='(A53)';
      BIDIRECTIONAL='TRUE';
      INPUT_LOAD='(-0.01,0.01)';
      OUTPUT_LOAD='(1.0,-1.0)';
    '-CHASI':
      PIN_NUMBER='(A54)';
      BIDIRECTIONAL='TRUE';
      INPUT_LOAD='(-0.01,0.01)';
      OUTPUT_LOAD='(1.0,-1.0)';
    'SPARE0':
      PIN_NUMBER='(A55)';
      BIDIRECTIONAL='TRUE';
      INPUT_LOAD='(-0.01,0.01)';
      OUTPUT_LOAD='(1.0,-1.0)';
    '-IRQ':
      PIN_NUMBER='(A56)';
      BIDIRECTIONAL='TRUE';
      INPUT_LOAD='(-0.01,0.01)';
      OUTPUT_LOAD='(1.0,-1.0)';
    '-PRSNT1':
      PIN_NUMBER='(A57)';
      BIDIRECTIONAL='TRUE';
      INPUT_LOAD='(-0.01,0.01)';
      OUTPUT_LOAD='(1.0,-1.0)';
    'GND_A58':
      PIN_NUMBER='(A58)';
      PINUSE='POWER';
      NO_LOAD_CHECK='Both';
      NO_IO_CHECK='Both';
      NO_ASSERT_CHECK='TRUE';
      NO_DIR_CHECK='TRUE';
      ALLOW_CONNECT='TRUE';
    'PCIE_HPM_RXP_0':
      PIN_NUMBER='(A59)';
      BIDIRECTIONAL='TRUE';
      INPUT_LOAD='(-0.01,0.01)';
      OUTPUT_LOAD='(1.0,-1.0)';
    'PCIE_HPM_RXN_0':
      PIN_NUMBER='(A60)';
      BIDIRECTIONAL='TRUE';
      INPUT_LOAD='(-0.01,0.01)';
      OUTPUT_LOAD='(1.0,-1.0)';
    'GND_A61':
      PIN_NUMBER='(A61)';
      PINUSE='POWER';
      NO_LOAD_CHECK='Both';
      NO_IO_CHECK='Both';
      NO_ASSERT_CHECK='TRUE';
      NO_DIR_CHECK='TRUE';
      ALLOW_CONNECT='TRUE';
    'PCIE_HPM_RXP_1':
      PIN_NUMBER='(A62)';
      BIDIRECTIONAL='TRUE';
      INPUT_LOAD='(-0.01,0.01)';
      OUTPUT_LOAD='(1.0,-1.0)';
    'PCIE_HPM_RXN_1':
      PIN_NUMBER='(A63)';
      BIDIRECTIONAL='TRUE';
      INPUT_LOAD='(-0.01,0.01)';
      OUTPUT_LOAD='(1.0,-1.0)';
    'GND_A64':
      PIN_NUMBER='(A64)';
      PINUSE='POWER';
      NO_LOAD_CHECK='Both';
      NO_IO_CHECK='Both';
      NO_ASSERT_CHECK='TRUE';
      NO_DIR_CHECK='TRUE';
      ALLOW_CONNECT='TRUE';
    'PCIE_HPM_RXP_2':
      PIN_NUMBER='(A65)';
      BIDIRECTIONAL='TRUE';
      INPUT_LOAD='(-0.01,0.01)';
      OUTPUT_LOAD='(1.0,-1.0)';
    'PCIE_HPM_RXN_2':
      PIN_NUMBER='(A66)';
      BIDIRECTIONAL='TRUE';
      INPUT_LOAD='(-0.01,0.01)';
      OUTPUT_LOAD='(1.0,-1.0)';
    'GND_A67':
      PIN_NUMBER='(A67)';
      PINUSE='POWER';
      NO_LOAD_CHECK='Both';
      NO_IO_CHECK='Both';
      NO_ASSERT_CHECK='TRUE';
      NO_DIR_CHECK='TRUE';
      ALLOW_CONNECT='TRUE';
    'PCIE_HPM_RXP_3':
      PIN_NUMBER='(A68)';
      BIDIRECTIONAL='TRUE';
      INPUT_LOAD='(-0.01,0.01)';
      OUTPUT_LOAD='(1.0,-1.0)';
    'PCIE_HPM_RXN_3':
      PIN_NUMBER='(A69)';
      BIDIRECTIONAL='TRUE';
      INPUT_LOAD='(-0.01,0.01)';
      OUTPUT_LOAD='(1.0,-1.0)';
    'GND_A70':
      PIN_NUMBER='(A70)';
      PINUSE='POWER';
      NO_LOAD_CHECK='Both';
      NO_IO_CHECK='Both';
      NO_ASSERT_CHECK='TRUE';
      NO_DIR_CHECK='TRUE';
      ALLOW_CONNECT='TRUE';
    'P12V_AUX_OB1':
      PIN_NUMBER='(OB1)';
      PINUSE='POWER';
      NO_LOAD_CHECK='Both';
      NO_IO_CHECK='Both';
      NO_ASSERT_CHECK='TRUE';
      NO_DIR_CHECK='TRUE';
      ALLOW_CONNECT='TRUE';
    'P12V_AUX_OB2':
      PIN_NUMBER='(OB2)';
      PINUSE='POWER';
      NO_LOAD_CHECK='Both';
      NO_IO_CHECK='Both';
      NO_ASSERT_CHECK='TRUE';
      NO_DIR_CHECK='TRUE';
      ALLOW_CONNECT='TRUE';
    '-PRSNT0':
      PIN_NUMBER='(OB3)';
      BIDIRECTIONAL='TRUE';
      INPUT_LOAD='(-0.01,0.01)';
      OUTPUT_LOAD='(1.0,-1.0)';
    'GND_OB4':
      PIN_NUMBER='(OB4)';
      PINUSE='POWER';
      NO_LOAD_CHECK='Both';
      NO_IO_CHECK='Both';
      NO_ASSERT_CHECK='TRUE';
      NO_DIR_CHECK='TRUE';
      ALLOW_CONNECT='TRUE';
    'UART1_SCM_TX':
      PIN_NUMBER='(OB5)';
      BIDIRECTIONAL='TRUE';
      INPUT_LOAD='(-0.01,0.01)';
      OUTPUT_LOAD='(1.0,-1.0)';
    'UART1_SCM_RX':
      PIN_NUMBER='(OB6)';
      BIDIRECTIONAL='TRUE';
      INPUT_LOAD='(-0.01,0.01)';
      OUTPUT_LOAD='(1.0,-1.0)';
    'GND_OB7':
      PIN_NUMBER='(OB7)';
      PINUSE='POWER';
      NO_LOAD_CHECK='Both';
      NO_IO_CHECK='Both';
      NO_ASSERT_CHECK='TRUE';
      NO_DIR_CHECK='TRUE';
      ALLOW_CONNECT='TRUE';
    'UART0_SCM_TX':
      PIN_NUMBER='(OB8)';
      BIDIRECTIONAL='TRUE';
      INPUT_LOAD='(-0.01,0.01)';
      OUTPUT_LOAD='(1.0,-1.0)';
    'UART0_SCM_RX':
      PIN_NUMBER='(OB9)';
      BIDIRECTIONAL='TRUE';
      INPUT_LOAD='(-0.01,0.01)';
      OUTPUT_LOAD='(1.0,-1.0)';
    'GND_OB10':
      PIN_NUMBER='(OB10)';
      PINUSE='POWER';
      NO_LOAD_CHECK='Both';
      NO_IO_CHECK='Both';
      NO_ASSERT_CHECK='TRUE';
      NO_DIR_CHECK='TRUE';
      ALLOW_CONNECT='TRUE';
    'SPI0_CLK':
      PIN_NUMBER='(OB11)';
      BIDIRECTIONAL='TRUE';
      INPUT_LOAD='(-0.01,0.01)';
      OUTPUT_LOAD='(1.0,-1.0)';
    '-SPI0_CS':
      PIN_NUMBER='(OB12)';
      BIDIRECTIONAL='TRUE';
      INPUT_LOAD='(-0.01,0.01)';
      OUTPUT_LOAD='(1.0,-1.0)';
    'SPI0_MOSI':
      PIN_NUMBER='(OB13)';
      BIDIRECTIONAL='TRUE';
      INPUT_LOAD='(-0.01,0.01)';
      OUTPUT_LOAD='(1.0,-1.0)';
    'SPI0_MISO':
      PIN_NUMBER='(OB14)';
      BIDIRECTIONAL='TRUE';
      INPUT_LOAD='(-0.01,0.01)';
      OUTPUT_LOAD='(1.0,-1.0)';
    'ESPI_CLK':
      PIN_NUMBER='(B1)';
      BIDIRECTIONAL='TRUE';
      INPUT_LOAD='(-0.01,0.01)';
      OUTPUT_LOAD='(1.0,-1.0)';
    '-ESPI_CS0':
      PIN_NUMBER='(B2)';
      BIDIRECTIONAL='TRUE';
      INPUT_LOAD='(-0.01,0.01)';
      OUTPUT_LOAD='(1.0,-1.0)';
    '-ESPI_ALERT':
      PIN_NUMBER='(B3)';
      BIDIRECTIONAL='TRUE';
      INPUT_LOAD='(-0.01,0.01)';
      OUTPUT_LOAD='(1.0,-1.0)';
    '-ESPI_RESET':
      PIN_NUMBER='(B4)';
      BIDIRECTIONAL='TRUE';
      INPUT_LOAD='(-0.01,0.01)';
      OUTPUT_LOAD='(1.0,-1.0)';
    'ESPI_IO0':
      PIN_NUMBER='(B5)';
      BIDIRECTIONAL='TRUE';
      INPUT_LOAD='(-0.01,0.01)';
      OUTPUT_LOAD='(1.0,-1.0)';
    'ESPI_IO1':
      PIN_NUMBER='(B6)';
      BIDIRECTIONAL='TRUE';
      INPUT_LOAD='(-0.01,0.01)';
      OUTPUT_LOAD='(1.0,-1.0)';
    'ESPI_IO2':
      PIN_NUMBER='(B7)';
      BIDIRECTIONAL='TRUE';
      INPUT_LOAD='(-0.01,0.01)';
      OUTPUT_LOAD='(1.0,-1.0)';
    'ESPI_IO3':
      PIN_NUMBER='(B8)';
      BIDIRECTIONAL='TRUE';
      INPUT_LOAD='(-0.01,0.01)';
      OUTPUT_LOAD='(1.0,-1.0)';
    'RSVD3':
      PIN_NUMBER='(B9)';
      BIDIRECTIONAL='TRUE';
      INPUT_LOAD='(-0.01,0.01)';
      OUTPUT_LOAD='(1.0,-1.0)';
    'GND_B10':
      PIN_NUMBER='(B10)';
      PINUSE='POWER';
      NO_LOAD_CHECK='Both';
      NO_IO_CHECK='Both';
      NO_ASSERT_CHECK='TRUE';
      NO_DIR_CHECK='TRUE';
      ALLOW_CONNECT='TRUE';
    'QSPI0_CLK':
      PIN_NUMBER='(B11)';
      BIDIRECTIONAL='TRUE';
      INPUT_LOAD='(-0.01,0.01)';
      OUTPUT_LOAD='(1.0,-1.0)';
    '-QSPI0_CS0':
      PIN_NUMBER='(B12)';
      BIDIRECTIONAL='TRUE';
      INPUT_LOAD='(-0.01,0.01)';
      OUTPUT_LOAD='(1.0,-1.0)';
    'QSPI0_D0':
      PIN_NUMBER='(B13)';
      BIDIRECTIONAL='TRUE';
      INPUT_LOAD='(-0.01,0.01)';
      OUTPUT_LOAD='(1.0,-1.0)';
    'QSPI0_D1':
      PIN_NUMBER='(B14)';
      BIDIRECTIONAL='TRUE';
      INPUT_LOAD='(-0.01,0.01)';
      OUTPUT_LOAD='(1.0,-1.0)';
    'QSPI0_D2':
      PIN_NUMBER='(B15)';
      BIDIRECTIONAL='TRUE';
      INPUT_LOAD='(-0.01,0.01)';
      OUTPUT_LOAD='(1.0,-1.0)';
    'QSPI0_D3':
      PIN_NUMBER='(B16)';
      BIDIRECTIONAL='TRUE';
      INPUT_LOAD='(-0.01,0.01)';
      OUTPUT_LOAD='(1.0,-1.0)';
    'GND_B17':
      PIN_NUMBER='(B17)';
      PINUSE='POWER';
      NO_LOAD_CHECK='Both';
      NO_IO_CHECK='Both';
      NO_ASSERT_CHECK='TRUE';
      NO_DIR_CHECK='TRUE';
      ALLOW_CONNECT='TRUE';
    'NCSI_CLK':
      PIN_NUMBER='(B18)';
      BIDIRECTIONAL='TRUE';
      INPUT_LOAD='(-0.01,0.01)';
      OUTPUT_LOAD='(1.0,-1.0)';
    'NCSI_CRS_DV':
      PIN_NUMBER='(B19)';
      BIDIRECTIONAL='TRUE';
      INPUT_LOAD='(-0.01,0.01)';
      OUTPUT_LOAD='(1.0,-1.0)';
    'NCSI_TXEN':
      PIN_NUMBER='(B20)';
      BIDIRECTIONAL='TRUE';
      INPUT_LOAD='(-0.01,0.01)';
      OUTPUT_LOAD='(1.0,-1.0)';
    'NCSI_TXD0':
      PIN_NUMBER='(B21)';
      BIDIRECTIONAL='TRUE';
      INPUT_LOAD='(-0.01,0.01)';
      OUTPUT_LOAD='(1.0,-1.0)';
    'NCSI_TXD1':
      PIN_NUMBER='(B22)';
      BIDIRECTIONAL='TRUE';
      INPUT_LOAD='(-0.01,0.01)';
      OUTPUT_LOAD='(1.0,-1.0)';
    'NCSI_RXER':
      PIN_NUMBER='(B23)';
      BIDIRECTIONAL='TRUE';
      INPUT_LOAD='(-0.01,0.01)';
      OUTPUT_LOAD='(1.0,-1.0)';
    'NCSI_RXD0':
      PIN_NUMBER='(B24)';
      BIDIRECTIONAL='TRUE';
      INPUT_LOAD='(-0.01,0.01)';
      OUTPUT_LOAD='(1.0,-1.0)';
    'NCSI_RXD1':
      PIN_NUMBER='(B25)';
      BIDIRECTIONAL='TRUE';
      INPUT_LOAD='(-0.01,0.01)';
      OUTPUT_LOAD='(1.0,-1.0)';
    'GND_B26':
      PIN_NUMBER='(B26)';
      PINUSE='POWER';
      NO_LOAD_CHECK='Both';
      NO_IO_CHECK='Both';
      NO_ASSERT_CHECK='TRUE';
      NO_DIR_CHECK='TRUE';
      ALLOW_CONNECT='TRUE';
    'PECI_BMC':
      PIN_NUMBER='(B27)';
      BIDIRECTIONAL='TRUE';
      INPUT_LOAD='(-0.01,0.01)';
      OUTPUT_LOAD='(1.0,-1.0)';
    'PVCCIO_PECI':
      PIN_NUMBER='(B28)';
      PINUSE='POWER';
      NO_LOAD_CHECK='Both';
      NO_IO_CHECK='Both';
      NO_ASSERT_CHECK='TRUE';
      NO_DIR_CHECK='TRUE';
      ALLOW_CONNECT='TRUE';
    'SGPIO0_DO':
      PIN_NUMBER='(B29)';
      BIDIRECTIONAL='TRUE';
      INPUT_LOAD='(-0.01,0.01)';
      OUTPUT_LOAD='(1.0,-1.0)';
    'SGPIO_CLK':
      PIN_NUMBER='(B30)';
      BIDIRECTIONAL='TRUE';
      INPUT_LOAD='(-0.01,0.01)';
      OUTPUT_LOAD='(1.0,-1.0)';
    'SGPIO0_DI':
      PIN_NUMBER='(B31)';
      BIDIRECTIONAL='TRUE';
      INPUT_LOAD='(-0.01,0.01)';
      OUTPUT_LOAD='(1.0,-1.0)';
    'SGPIO0_LD':
      PIN_NUMBER='(B32)';
      BIDIRECTIONAL='TRUE';
      INPUT_LOAD='(-0.01,0.01)';
      OUTPUT_LOAD='(1.0,-1.0)';
    'GND_B33':
      PIN_NUMBER='(B33)';
      PINUSE='POWER';
      NO_LOAD_CHECK='Both';
      NO_IO_CHECK='Both';
      NO_ASSERT_CHECK='TRUE';
      NO_DIR_CHECK='TRUE';
      ALLOW_CONNECT='TRUE';
    'SGPIO1_DO':
      PIN_NUMBER='(B34)';
      BIDIRECTIONAL='TRUE';
      INPUT_LOAD='(-0.01,0.01)';
      OUTPUT_LOAD='(1.0,-1.0)';
    'RSVD2':
      PIN_NUMBER='(B35)';
      OUTPUT_TYPE='(TS,TS)';
      INPUT_LOAD='(-0.01,0.01)';
      OUTPUT_LOAD='(1.0,-1.0)';
    'SGPIO1_DI':
      PIN_NUMBER='(B36)';
      BIDIRECTIONAL='TRUE';
      INPUT_LOAD='(-0.01,0.01)';
      OUTPUT_LOAD='(1.0,-1.0)';
    'SGPIO1_LD':
      PIN_NUMBER='(B37)';
      BIDIRECTIONAL='TRUE';
      INPUT_LOAD='(-0.01,0.01)';
      OUTPUT_LOAD='(1.0,-1.0)';
    'GND_B38':
      PIN_NUMBER='(B38)';
      PINUSE='POWER';
      NO_LOAD_CHECK='Both';
      NO_IO_CHECK='Both';
      NO_ASSERT_CHECK='TRUE';
      NO_DIR_CHECK='TRUE';
      ALLOW_CONNECT='TRUE';
    '-SGPIO_RESET':
      PIN_NUMBER='(B39)';
      BIDIRECTIONAL='TRUE';
      INPUT_LOAD='(-0.01,0.01)';
      OUTPUT_LOAD='(1.0,-1.0)';
    '-SGPIO_INTR':
      PIN_NUMBER='(B40)';
      BIDIRECTIONAL='TRUE';
      INPUT_LOAD='(-0.01,0.01)';
      OUTPUT_LOAD='(1.0,-1.0)';
    'P3V0_BAT':
      PIN_NUMBER='(B41)';
      PINUSE='POWER';
      NO_LOAD_CHECK='Both';
      NO_IO_CHECK='Both';
      NO_ASSERT_CHECK='TRUE';
      NO_DIR_CHECK='TRUE';
      ALLOW_CONNECT='TRUE';
    '-QSPI0_CS1':
      PIN_NUMBER='(B42)';
      BIDIRECTIONAL='TRUE';
      INPUT_LOAD='(-0.01,0.01)';
      OUTPUT_LOAD='(1.0,-1.0)';
    'QSPI1_CLK':
      PIN_NUMBER='(B43)';
      BIDIRECTIONAL='TRUE';
      INPUT_LOAD='(-0.01,0.01)';
      OUTPUT_LOAD='(1.0,-1.0)';
    '-QSPI1_CS0':
      PIN_NUMBER='(B44)';
      BIDIRECTIONAL='TRUE';
      INPUT_LOAD='(-0.01,0.01)';
      OUTPUT_LOAD='(1.0,-1.0)';
    'QSPI1_D0':
      PIN_NUMBER='(B45)';
      BIDIRECTIONAL='TRUE';
      INPUT_LOAD='(-0.01,0.01)';
      OUTPUT_LOAD='(1.0,-1.0)';
    'QSPI1_D1':
      PIN_NUMBER='(B46)';
      BIDIRECTIONAL='TRUE';
      INPUT_LOAD='(-0.01,0.01)';
      OUTPUT_LOAD='(1.0,-1.0)';
    'QSPI1_D2':
      PIN_NUMBER='(B47)';
      BIDIRECTIONAL='TRUE';
      INPUT_LOAD='(-0.01,0.01)';
      OUTPUT_LOAD='(1.0,-1.0)';
    'QSPI1_D3':
      PIN_NUMBER='(B48)';
      BIDIRECTIONAL='TRUE';
      INPUT_LOAD='(-0.01,0.01)';
      OUTPUT_LOAD='(1.0,-1.0)';
    'GND_B49':
      PIN_NUMBER='(B49)';
      PINUSE='POWER';
      NO_LOAD_CHECK='Both';
      NO_IO_CHECK='Both';
      NO_ASSERT_CHECK='TRUE';
      NO_DIR_CHECK='TRUE';
      ALLOW_CONNECT='TRUE';
    'USB2_DP':
      PIN_NUMBER='(B50)';
      BIDIRECTIONAL='TRUE';
      INPUT_LOAD='(-0.01,0.01)';
      OUTPUT_LOAD='(1.0,-1.0)';
    'USB2_DN':
      PIN_NUMBER='(B51)';
      BIDIRECTIONAL='TRUE';
      INPUT_LOAD='(-0.01,0.01)';
      OUTPUT_LOAD='(1.0,-1.0)';
    'GND_B52':
      PIN_NUMBER='(B52)';
      PINUSE='POWER';
      NO_LOAD_CHECK='Both';
      NO_IO_CHECK='Both';
      NO_ASSERT_CHECK='TRUE';
      NO_DIR_CHECK='TRUE';
      ALLOW_CONNECT='TRUE';
    'USB1_DP':
      PIN_NUMBER='(B53)';
      BIDIRECTIONAL='TRUE';
      INPUT_LOAD='(-0.01,0.01)';
      OUTPUT_LOAD='(1.0,-1.0)';
    'USB1_DN':
      PIN_NUMBER='(B54)';
      BIDIRECTIONAL='TRUE';
      INPUT_LOAD='(-0.01,0.01)';
      OUTPUT_LOAD='(1.0,-1.0)';
    'GND_B55':
      PIN_NUMBER='(B55)';
      PINUSE='POWER';
      NO_LOAD_CHECK='Both';
      NO_IO_CHECK='Both';
      NO_ASSERT_CHECK='TRUE';
      NO_DIR_CHECK='TRUE';
      ALLOW_CONNECT='TRUE';
    'RSVD0':
      PIN_NUMBER='(B56)';
      OUTPUT_TYPE='(TS,TS)';
      INPUT_LOAD='(-0.01,0.01)';
      OUTPUT_LOAD='(1.0,-1.0)';
    'RSVD1':
      PIN_NUMBER='(B57)';
      OUTPUT_TYPE='(TS,TS)';
      INPUT_LOAD='(-0.01,0.01)';
      OUTPUT_LOAD='(1.0,-1.0)';
    'GND_B58':
      PIN_NUMBER='(B58)';
      PINUSE='POWER';
      NO_LOAD_CHECK='Both';
      NO_IO_CHECK='Both';
      NO_ASSERT_CHECK='TRUE';
      NO_DIR_CHECK='TRUE';
      ALLOW_CONNECT='TRUE';
    'PCIE_HPM_TXP_0':
      PIN_NUMBER='(B59)';
      BIDIRECTIONAL='TRUE';
      INPUT_LOAD='(-0.01,0.01)';
      OUTPUT_LOAD='(1.0,-1.0)';
    'PCIE_HPM_TXN_0':
      PIN_NUMBER='(B60)';
      BIDIRECTIONAL='TRUE';
      INPUT_LOAD='(-0.01,0.01)';
      OUTPUT_LOAD='(1.0,-1.0)';
    'GND_B61':
      PIN_NUMBER='(B61)';
      PINUSE='POWER';
      NO_LOAD_CHECK='Both';
      NO_IO_CHECK='Both';
      NO_ASSERT_CHECK='TRUE';
      NO_DIR_CHECK='TRUE';
      ALLOW_CONNECT='TRUE';
    'PCIE_HPM_TXP_1':
      PIN_NUMBER='(B62)';
      BIDIRECTIONAL='TRUE';
      INPUT_LOAD='(-0.01,0.01)';
      OUTPUT_LOAD='(1.0,-1.0)';
    'PCIE_HPM_TXN_1':
      PIN_NUMBER='(B63)';
      BIDIRECTIONAL='TRUE';
      INPUT_LOAD='(-0.01,0.01)';
      OUTPUT_LOAD='(1.0,-1.0)';
    'GND_B64':
      PIN_NUMBER='(B64)';
      PINUSE='POWER';
      NO_LOAD_CHECK='Both';
      NO_IO_CHECK='Both';
      NO_ASSERT_CHECK='TRUE';
      NO_DIR_CHECK='TRUE';
      ALLOW_CONNECT='TRUE';
    'PCIE_HPM_TXP_2':
      PIN_NUMBER='(B65)';
      BIDIRECTIONAL='TRUE';
      INPUT_LOAD='(-0.01,0.01)';
      OUTPUT_LOAD='(1.0,-1.0)';
    'PCIE_HPM_TXN_2':
      PIN_NUMBER='(B66)';
      BIDIRECTIONAL='TRUE';
      INPUT_LOAD='(-0.01,0.01)';
      OUTPUT_LOAD='(1.0,-1.0)';
    'GND_B67':
      PIN_NUMBER='(B67)';
      PINUSE='POWER';
      NO_LOAD_CHECK='Both';
      NO_IO_CHECK='Both';
      NO_ASSERT_CHECK='TRUE';
      NO_DIR_CHECK='TRUE';
      ALLOW_CONNECT='TRUE';
    'PCIE_HPM_TXP_3':
      PIN_NUMBER='(B68)';
      BIDIRECTIONAL='TRUE';
      INPUT_LOAD='(-0.01,0.01)';
      OUTPUT_LOAD='(1.0,-1.0)';
    'PCIE_HPM_TXN_3':
      PIN_NUMBER='(B69)';
      BIDIRECTIONAL='TRUE';
      INPUT_LOAD='(-0.01,0.01)';
      OUTPUT_LOAD='(1.0,-1.0)';
    'GND_B70':
      PIN_NUMBER='(B70)';
      PINUSE='POWER';
      NO_LOAD_CHECK='Both';
      NO_IO_CHECK='Both';
      NO_ASSERT_CHECK='TRUE';
      NO_DIR_CHECK='TRUE';
      ALLOW_CONNECT='TRUE';
  end_pin;
  body
    PART_NAME='FCONN168_ME1016810202011_SCM';
    BODY_NAME='FCONN168_ME1016810202011_SCM';
    PHYS_DES_PREFIX='GF';
    CLASS='DISCRETE';
  end_body;
end_primitive;

END.
